(kicad_pcb
	(version 20260206)
	(generator "pcbnew")
	(generator_version "10.0")
	(general
		(thickness 1.6)
		(legacy_teardrops no)
	)
	(paper "A4")
	(title_block
		(title "dpb — 14545-sa.0730WZS0815.brd")
		(comment 1 "Honey Badger (Wiwynn) / footprints 1034-1036 of 1066")
	)
	(layers
		(0 "F.Cu" signal "TOP")
		(4 "In1.Cu" signal "L2GND")
		(6 "In2.Cu" signal "L3")
		(8 "In3.Cu" signal "L4VCC")
		(10 "In4.Cu" signal "L5VCC")
		(12 "In5.Cu" signal "L6")
		(14 "In6.Cu" signal "L7GND")
		(2 "B.Cu" signal "BOTTOM")
		(9 "F.Adhes" user "F.Adhesive")
		(11 "B.Adhes" user "B.Adhesive")
		(13 "F.Paste" user "Package Geometry/Pastemask Top")
		(15 "B.Paste" user "Package Geometry/Pastemask Bottom")
		(5 "F.SilkS" user "Ref Des/Silkscreen Top")
		(7 "B.SilkS" user "Ref Des/Silkscreen Bottom")
		(1 "F.Mask" user "Board Geometry/Soldermask Top")
		(3 "B.Mask" user "Board Geometry/Soldermask Bottom")
		(17 "Dwgs.User" user "User.Drawings")
		(19 "Cmts.User" user "User.Comments")
		(21 "Eco1.User" user "User.Eco1")
		(23 "Eco2.User" user "User.Eco2")
		(25 "Edge.Cuts" user "Board Geometry/Outline")
		(27 "Margin" user)
		(31 "F.CrtYd" user "Package Geometry/Place Bound Top")
		(29 "B.CrtYd" user "Package Geometry/Place Bound Bottom")
		(35 "F.Fab" user "Ref Des/Assembly Top")
		(33 "B.Fab" user "Ref Des/Assembly Bottom")
	)
	(footprint ""
		(layer "F.Cu")
		(at 42.500042 -376.670062 90)
		(property "Reference" "SKT7"
			(at 0 0 90)
			(layer "F.SilkS")
			(hide yes)
			(effects
				(font
					(size 1.27 1.27)
				)
			)
		)
		(property "Value" "SKT-SATA14P-15P-12-GP"
			(at -22.6187 8.1788 90)
			(unlocked yes)
			(layer "F.Fab")
			(hide yes)
			(effects
				(font
					(size 1.016 1.016)
					(thickness 0.1524)
				)
			)
		)
		(property "Device Type" "87945-1001"
			(at -22.6187 6.6548 90)
			(unlocked yes)
			(layer "F.Fab")
			(hide yes)
			(effects
				(font
					(size 1.016 1.016)
					(thickness 0.1524)
				)
			)
		)
		(duplicate_pad_numbers_are_jumpers no)
		(fp_line
			(start -15.3924 -5.8547)
			(end -16.3576 -5.8547)
			(stroke
				(width 0.3302)
				(type default)
			)
			(layer "F.SilkS")
		)
		(fp_line
			(start 20.4724 -5.7658)
			(end 20.4724 -2.3114)
			(stroke
				(width 0.1524)
				(type default)
			)
			(layer "F.SilkS")
		)
		(fp_line
			(start -20.4724 -5.7658)
			(end 20.4724 -5.7658)
			(stroke
				(width 0.1524)
				(type default)
			)
			(layer "F.SilkS")
		)
		(fp_line
			(start 23.7617 -2.3114)
			(end 23.7617 2.3114)
			(stroke
				(width 0.1524)
				(type default)
			)
			(layer "F.SilkS")
		)
		(fp_line
			(start 20.4724 -2.3114)
			(end 23.7617 -2.3114)
			(stroke
				(width 0.1524)
				(type default)
			)
			(layer "F.SilkS")
		)
		(fp_line
			(start -20.4724 -2.3114)
			(end -20.4724 -5.7658)
			(stroke
				(width 0.1524)
				(type default)
			)
			(layer "F.SilkS")
		)
		(fp_line
			(start -23.7617 -2.3114)
			(end -20.4724 -2.3114)
			(stroke
				(width 0.1524)
				(type default)
			)
			(layer "F.SilkS")
		)
		(fp_line
			(start 23.117556 -0.5461)
			(end 23.117556 0.5461)
			(stroke
				(width 0.3048)
				(type default)
			)
			(layer "F.SilkS")
		)
		(fp_line
			(start -20.882356 -0.5461)
			(end -20.882356 0.5461)
			(stroke
				(width 0.3048)
				(type default)
			)
			(layer "F.SilkS")
		)
		(fp_line
			(start 20.882356 0.5461)
			(end 20.882356 -0.5461)
			(stroke
				(width 0.3048)
				(type default)
			)
			(layer "F.SilkS")
		)
		(fp_line
			(start -23.117556 0.5461)
			(end -23.117556 -0.5461)
			(stroke
				(width 0.3048)
				(type default)
			)
			(layer "F.SilkS")
		)
		(fp_line
			(start 23.7617 2.3114)
			(end 20.4724 2.3114)
			(stroke
				(width 0.1524)
				(type default)
			)
			(layer "F.SilkS")
		)
		(fp_line
			(start 20.4724 2.3114)
			(end 20.4724 9.652)
			(stroke
				(width 0.1524)
				(type default)
			)
			(layer "F.SilkS")
		)
		(fp_line
			(start -20.4724 2.3114)
			(end -23.7617 2.3114)
			(stroke
				(width 0.1524)
				(type default)
			)
			(layer "F.SilkS")
		)
		(fp_line
			(start -23.7617 2.3114)
			(end -23.7617 -2.3114)
			(stroke
				(width 0.1524)
				(type default)
			)
			(layer "F.SilkS")
		)
		(fp_line
			(start 17.8435 7.9502)
			(end -17.8435 7.9502)
			(stroke
				(width 0.1524)
				(type default)
			)
			(layer "F.SilkS")
		)
		(fp_line
			(start -17.8435 7.9502)
			(end -17.8435 9.652)
			(stroke
				(width 0.1524)
				(type default)
			)
			(layer "F.SilkS")
		)
		(fp_line
			(start 20.4724 9.652)
			(end 17.8435 9.652)
			(stroke
				(width 0.1524)
				(type default)
			)
			(layer "F.SilkS")
		)
		(fp_line
			(start 17.8435 9.652)
			(end 17.8435 7.9502)
			(stroke
				(width 0.1524)
				(type default)
			)
			(layer "F.SilkS")
		)
		(fp_line
			(start -17.8435 9.652)
			(end -20.4724 9.652)
			(stroke
				(width 0.1524)
				(type default)
			)
			(layer "F.SilkS")
		)
		(fp_line
			(start -20.4724 9.652)
			(end -20.4724 2.3114)
			(stroke
				(width 0.1524)
				(type default)
			)
			(layer "F.SilkS")
		)
		(fp_arc
			(start 20.882356 -0.5461)
			(mid 21.999956 -1.6637)
			(end 23.117556 -0.5461)
			(stroke
				(width 0.3048)
				(type default)
			)
			(layer "F.SilkS")
		)
		(fp_arc
			(start -23.117556 -0.5461)
			(mid -21.999956 -1.6637)
			(end -20.882356 -0.5461)
			(stroke
				(width 0.3048)
				(type default)
			)
			(layer "F.SilkS")
		)
		(fp_arc
			(start 23.117556 0.5461)
			(mid 21.999956 1.6637)
			(end 20.882356 0.5461)
			(stroke
				(width 0.3048)
				(type default)
			)
			(layer "F.SilkS")
		)
		(fp_arc
			(start -20.882356 0.5461)
			(mid -21.999956 1.6637)
			(end -23.117556 0.5461)
			(stroke
				(width 0.3048)
				(type default)
			)
			(layer "F.SilkS")
		)
		(fp_poly
			(pts
				(xy -15.87119 -5.838698) (xy -15.23619 -6.473698) (xy -16.50619 -6.473698)
			)
			(stroke
				(width 0)
				(type default)
			)
			(fill yes)
			(layer "F.SilkS")
		)
		(fp_poly
			(pts
				(xy -20.2184 -5.5118) (xy 20.2184 -5.5118) (xy 20.2184 -2.0574) (xy 23.5077 -2.0574) (xy 23.5077 2.0574)
				(xy 20.2184 2.0574) (xy 20.2184 9.398) (xy 18.0975 9.398) (xy 18.0975 7.6962) (xy -18.0975 7.6962)
				(xy -18.0975 9.398) (xy -20.2184 9.398) (xy -20.2184 2.0574) (xy -23.5077 2.0574) (xy -23.5077 -2.0574)
				(xy -20.2184 -2.0574)
			)
			(stroke
				(width 0)
				(type default)
			)
			(fill no)
			(layer "F.CrtYd")
		)
		(fp_poly
			(pts
				(xy -20.2184 -5.5118) (xy -20.2184 -6.0198) (xy -20.7264 -6.0198) (xy -20.7264 -2.5654) (xy -24.0157 -2.5654)
				(xy -24.0157 2.5654) (xy -20.7264 2.5654) (xy -20.7264 9.906) (xy -17.5895 9.906) (xy -17.5895 8.2042)
				(xy 17.5895 8.2042) (xy 17.5895 9.906) (xy 20.7264 9.906) (xy 20.7264 2.5654) (xy 24.0157 2.5654)
				(xy 24.0157 -2.5654) (xy 20.7264 -2.5654) (xy 20.7264 -6.0198) (xy -20.21586 -6.0198) (xy -20.21586 -5.5118)
				(xy 20.2184 -5.5118) (xy 20.2184 -2.0574) (xy 23.5077 -2.0574) (xy 23.5077 2.0574) (xy 20.2184 2.0574)
				(xy 20.2184 9.398) (xy 18.0975 9.398) (xy 18.0975 7.6962) (xy -18.0975 7.6962) (xy -18.0975 9.398)
				(xy -20.2184 9.398) (xy -20.2184 2.0574) (xy -23.5077 2.0574) (xy -23.5077 -2.0574) (xy -20.2184 -2.0574)
			)
			(stroke
				(width 0)
				(type default)
			)
			(fill no)
			(layer "F.CrtYd")
		)
		(fp_poly
			(pts
				(xy -20.7264 -6.0198) (xy -20.7264 -2.5654) (xy -24.0157 -2.5654) (xy -24.0157 2.5654) (xy -20.7264 2.5654)
				(xy -20.7264 9.906) (xy -17.5895 9.906) (xy -17.5895 8.2042) (xy 17.5895 8.2042) (xy 17.5895 9.906)
				(xy 20.7264 9.906) (xy 20.7264 2.5654) (xy 24.0157 2.5654) (xy 24.0157 -2.5654) (xy 20.7264 -2.5654)
				(xy 20.7264 -6.0198)
			)
			(stroke
				(width 0)
				(type default)
			)
			(fill no)
			(layer "F.Fab")
		)
		(pad "" np_thru_hole circle
			(at -18.999962 -2.350008 90)
			(size 0.254 0.254)
			(drill 1.8542)
			(layers "*.Cu" "*.Mask")
			(clearance 1.1557)
			(thermal_gap 1.1557)
		)
		(pad "" np_thru_hole circle
			(at 18.999962 -2.350008 90)
			(size 0.254 0.254)
			(drill 1.8542)
			(layers "*.Cu" "*.Mask")
			(clearance 1.1557)
			(thermal_gap 1.1557)
		)
		(pad "H1" thru_hole oval
			(at -21.999956 0 90)
			(size 1.524 2.6162)
			(drill oval 0.8128 1.905)
			(layers "*.Cu" "*.Mask")
			(remove_unused_layers no)
			(net "GND")
			(clearance 0.1524)
			(thermal_gap 0.1524)
		)
		(pad "H2" thru_hole oval
			(at 21.999956 0 90)
			(size 1.524 2.6162)
			(drill oval 0.8128 1.905)
			(layers "*.Cu" "*.Mask")
			(remove_unused_layers no)
			(net "GND")
			(clearance 0.1524)
			(thermal_gap 0.1524)
		)
		(pad "P1" smd rect
			(at -1.89992 -4.249928 90)
			(size 0.6604 2.3876)
			(layers "F.Cu" "F.Mask" "F.Paste")
			(net "Net_15")
		)
		(pad "P2" smd rect
			(at -0.62992 -4.249928 90)
			(size 0.6604 2.3876)
			(layers "F.Cu" "F.Mask" "F.Paste")
			(net "Net_14")
		)
		(pad "P3" smd rect
			(at 0.64008 -4.249928 90)
			(size 0.6604 2.3876)
			(layers "F.Cu" "F.Mask" "F.Paste")
			(net "Net_13")
		)
		(pad "P4" smd rect
			(at 1.91008 -4.249928 90)
			(size 0.6604 2.3876)
			(layers "F.Cu" "F.Mask" "F.Paste")
			(net "GND")
		)
		(pad "P5" smd rect
			(at 3.18008 -4.249928 90)
			(size 0.6604 2.3876)
			(layers "F.Cu" "F.Mask" "F.Paste")
			(net "HDD_PRSNT_NET6")
		)
		(pad "P6" smd rect
			(at 4.45008 -4.249928 90)
			(size 0.6604 2.3876)
			(layers "F.Cu" "F.Mask" "F.Paste")
			(net "GND")
		)
		(pad "P7" smd rect
			(at 5.72008 -4.249928 90)
			(size 0.6604 2.3876)
			(layers "F.Cu" "F.Mask" "F.Paste")
			(net "5V_PRE_6")
		)
		(pad "P8" smd rect
			(at 6.99008 -4.249928 90)
			(size 0.6604 2.3876)
			(layers "F.Cu" "F.Mask" "F.Paste")
			(net "P5V_HDD6")
		)
		(pad "P9" smd rect
			(at 8.26008 -4.249928 90)
			(size 0.6604 2.3876)
			(layers "F.Cu" "F.Mask" "F.Paste")
			(net "P5V_HDD6")
		)
		(pad "P10" smd rect
			(at 9.53008 -4.249928 90)
			(size 0.6604 2.3876)
			(layers "F.Cu" "F.Mask" "F.Paste")
			(net "GND")
		)
		(pad "P11" smd rect
			(at 10.80008 -4.249928 90)
			(size 0.6604 2.3876)
			(layers "F.Cu" "F.Mask" "F.Paste")
			(net "ACT_HDD6")
		)
		(pad "P12" smd rect
			(at 12.07008 -4.249928 90)
			(size 0.6604 2.3876)
			(layers "F.Cu" "F.Mask" "F.Paste")
			(net "GND")
		)
		(pad "P13" smd rect
			(at 13.34008 -4.249928 90)
			(size 0.6604 2.3876)
			(layers "F.Cu" "F.Mask" "F.Paste")
			(net "12V_PRE_6")
		)
		(pad "P14" smd rect
			(at 14.61008 -4.249928 90)
			(size 0.6604 2.3876)
			(layers "F.Cu" "F.Mask" "F.Paste")
			(net "P12V_HDD6")
		)
		(pad "P15" smd rect
			(at 15.88008 -4.249928 90)
			(size 0.6604 2.3876)
			(layers "F.Cu" "F.Mask" "F.Paste")
			(net "P12V_HDD6")
		)
		(pad "S1" smd rect
			(at -15.86992 -4.249928 90)
			(size 0.6604 2.3876)
			(layers "F.Cu" "F.Mask" "F.Paste")
			(net "GND")
		)
		(pad "S2" smd rect
			(at -14.59992 -4.249928 90)
			(size 0.6604 2.3876)
			(layers "F.Cu" "F.Mask" "F.Paste")
			(net "SAS2X28_A_HDD6_TX_+")
		)
		(pad "S3" smd rect
			(at -13.32992 -4.249928 90)
			(size 0.6604 2.3876)
			(layers "F.Cu" "F.Mask" "F.Paste")
			(net "SAS2X28_A_HDD6_TX_-")
		)
		(pad "S4" smd rect
			(at -12.05992 -4.249928 90)
			(size 0.6604 2.3876)
			(layers "F.Cu" "F.Mask" "F.Paste")
			(net "GND")
		)
		(pad "S5" smd rect
			(at -10.78992 -4.249928 90)
			(size 0.6604 2.3876)
			(layers "F.Cu" "F.Mask" "F.Paste")
			(net "SAS2X28_DRIVE_RX_N_A6")
		)
		(pad "S6" smd rect
			(at -9.51992 -4.249928 90)
			(size 0.6604 2.3876)
			(layers "F.Cu" "F.Mask" "F.Paste")
			(net "SAS2X28_DRIVE_RX_P_A6")
		)
		(pad "S7" smd rect
			(at -8.24992 -4.249928 90)
			(size 0.6604 2.3876)
			(layers "F.Cu" "F.Mask" "F.Paste")
			(net "GND")
		)
		(pad "S8" smd rect
			(at -7.480046 -2.100072 90)
			(size 0.508 1.905)
			(layers "F.Cu" "F.Mask" "F.Paste")
			(net "GND")
		)
		(pad "S9" smd rect
			(at -6.679946 -2.100072 90)
			(size 0.508 1.905)
			(layers "F.Cu" "F.Mask" "F.Paste")
			(net "SAS2X28_B_HDD6_TX_+")
		)
		(pad "S10" smd rect
			(at -5.8801 -2.100072 90)
			(size 0.508 1.905)
			(layers "F.Cu" "F.Mask" "F.Paste")
			(net "SAS2X28_B_HDD6_TX_-")
		)
		(pad "S11" smd rect
			(at -5.08 -2.100072 90)
			(size 0.508 1.905)
			(layers "F.Cu" "F.Mask" "F.Paste")
			(net "GND")
		)
		(pad "S12" smd rect
			(at -4.2799 -2.100072 90)
			(size 0.508 1.905)
			(layers "F.Cu" "F.Mask" "F.Paste")
			(net "SAS2X28_DRIVE_RX_N_B6")
		)
		(pad "S13" smd rect
			(at -3.480054 -2.100072 90)
			(size 0.508 1.905)
			(layers "F.Cu" "F.Mask" "F.Paste")
			(net "SAS2X28_DRIVE_RX_P_B6")
		)
		(pad "S14" smd rect
			(at -2.679954 -2.100072 90)
			(size 0.508 1.905)
			(layers "F.Cu" "F.Mask" "F.Paste")
			(net "GND")
		)
		(zone
			(layers "F.Cu" "B.Cu" "In1.Cu" "In2.Cu" "In3.Cu" "In4.Cu" "In5.Cu" "In6.Cu")
			(hatch none 0.5)
			(connect_pads
				(clearance 0)
			)
			(min_thickness 0.25)
			(keepout
				(tracks not_allowed)
				(vias allowed)
				(pads allowed)
				(copperpour not_allowed)
				(footprints allowed)
			)
			(placement
				(enabled no)
				(sheetname "")
			)
			(fill
				(thermal_gap 0.5)
				(thermal_bridge_width 0.5)
				(island_removal_mode 0)
			)
			(polygon
				(pts
					(arc
						(start 41.381934 -395.670024)
						(mid 38.918134 -395.670024)
						(end 41.381934 -395.670024)
					)
				)
			)
		)
		(zone
			(layers "F.Cu" "B.Cu" "In1.Cu" "In2.Cu" "In3.Cu" "In4.Cu" "In5.Cu" "In6.Cu")
			(hatch none 0.5)
			(connect_pads
				(clearance 0)
			)
			(min_thickness 0.25)
			(keepout
				(tracks not_allowed)
				(vias allowed)
				(pads allowed)
				(copperpour not_allowed)
				(footprints allowed)
			)
			(placement
				(enabled no)
				(sheetname "")
			)
			(fill
				(thermal_gap 0.5)
				(thermal_bridge_width 0.5)
				(island_removal_mode 0)
			)
			(polygon
				(pts
					(arc
						(start 41.381934 -357.6701)
						(mid 38.918134 -357.6701)
						(end 41.381934 -357.6701)
					)
				)
			)
		)
	)
	(footprint ""
		(layer "F.Cu")
		(at 20.193254 -155.3083 -90)
		(property "Reference" "R283"
			(at 0 0 270)
			(layer "F.SilkS")
			(hide yes)
			(effects
				(font
					(size 1.27 1.27)
				)
			)
		)
		(property "Value" "402R2F-GP"
			(at 0.064008 -3.993896 270)
			(unlocked yes)
			(layer "F.Fab")
			(hide yes)
			(effects
				(font
					(size 1.016 1.016)
					(thickness 0.1524)
				)
			)
		)
		(property "Device Type" "R402H16"
			(at 0.064008 -5.517896 270)
			(unlocked yes)
			(layer "F.Fab")
			(hide yes)
			(effects
				(font
					(size 1.016 1.016)
					(thickness 0.1524)
				)
			)
		)
		(duplicate_pad_numbers_are_jumpers no)
		(fp_line
			(start -0.508 -0.9398)
			(end -0.508 0.9398)
			(stroke
				(width 0.1524)
				(type default)
			)
			(layer "F.SilkS")
		)
		(fp_line
			(start 0.508 -0.9398)
			(end -0.508 -0.9398)
			(stroke
				(width 0.1524)
				(type default)
			)
			(layer "F.SilkS")
		)
		(fp_rect
			(start -0.508 0.9398)
			(end 0.508 -0.9398)
			(stroke
				(width 0)
				(type default)
			)
			(fill no)
			(layer "F.CrtYd")
		)
		(fp_rect
			(start -0.508 0.9398)
			(end 0.508 -0.9398)
			(stroke
				(width 0)
				(type default)
			)
			(fill no)
			(layer "F.Fab")
		)
		(pad "1" smd custom
			(at 0 -0.4445 270)
			(size 0.1397 0.1397)
			(layers "F.Cu" "F.Mask" "F.Paste")
			(net "P5VC_HDD13_LED")
			(options
				(clearance outline)
				(anchor circle)
			)
			(primitives
				(gr_poly
					(pts
						(arc
							(start -0.1778 -0.2794)
							(mid -0.249642 -0.249642)
							(end -0.2794 -0.1778)
						)
						(arc
							(start -0.2794 0.1778)
							(mid -0.249642 0.249642)
							(end -0.1778 0.2794)
						)
						(arc
							(start 0.1778 0.2794)
							(mid 0.249642 0.249642)
							(end 0.2794 0.1778)
						)
						(arc
							(start 0.2794 -0.1778)
							(mid 0.249642 -0.249642)
							(end 0.1778 -0.2794)
						)
					)
					(width 0)
					(fill yes)
				)
			)
		)
		(pad "2" smd custom
			(at 0 0.4445 270)
			(size 0.1397 0.1397)
			(layers "F.Cu" "F.Mask" "F.Paste")
			(net "DRV_ACT_13")
			(options
				(clearance outline)
				(anchor circle)
			)
			(primitives
				(gr_poly
					(pts
						(arc
							(start -0.1778 -0.2794)
							(mid -0.249642 -0.249642)
							(end -0.2794 -0.1778)
						)
						(arc
							(start -0.2794 0.1778)
							(mid -0.249642 0.249642)
							(end -0.1778 0.2794)
						)
						(arc
							(start 0.1778 0.2794)
							(mid 0.249642 0.249642)
							(end 0.2794 0.1778)
						)
						(arc
							(start 0.2794 -0.1778)
							(mid 0.249642 -0.249642)
							(end 0.1778 -0.2794)
						)
					)
					(width 0)
					(fill yes)
				)
			)
		)
	)
	(footprint ""
		(layer "F.Cu")
		(at 25.298146 -273.6596 90)
		(property "Reference" "R494"
			(at 0 0 90)
			(layer "F.SilkS")
			(hide yes)
			(effects
				(font
					(size 1.27 1.27)
				)
			)
		)
		(property "Value" "4K7R2J-2-GP"
			(at 0.064008 -3.993896 90)
			(unlocked yes)
			(layer "F.Fab")
			(hide yes)
			(effects
				(font
					(size 1.016 1.016)
					(thickness 0.1524)
				)
			)
		)
		(property "Device Type" "R402H16"
			(at 0.064008 -5.517896 90)
			(unlocked yes)
			(layer "F.Fab")
			(hide yes)
			(effects
				(font
					(size 1.016 1.016)
					(thickness 0.1524)
				)
			)
		)
		(duplicate_pad_numbers_are_jumpers no)
		(fp_line
			(start 0.508 -0.9398)
			(end -0.508 -0.9398)
			(stroke
				(width 0.1524)
				(type default)
			)
			(layer "F.SilkS")
		)
		(fp_line
			(start -0.508 -0.9398)
			(end -0.508 0.9398)
			(stroke
				(width 0.1524)
				(type default)
			)
			(layer "F.SilkS")
		)
		(fp_rect
			(start -0.508 0.9398)
			(end 0.508 -0.9398)
			(stroke
				(width 0)
				(type default)
			)
			(fill no)
			(layer "F.CrtYd")
		)
		(fp_rect
			(start -0.508 0.9398)
			(end 0.508 -0.9398)
			(stroke
				(width 0)
				(type default)
			)
			(fill no)
			(layer "F.Fab")
		)
		(pad "1" smd custom
			(at 0 -0.4445 90)
			(size 0.1397 0.1397)
			(layers "F.Cu" "F.Mask" "F.Paste")
			(net "P3V3")
			(options
				(clearance outline)
				(anchor circle)
			)
			(primitives
				(gr_poly
					(pts
						(arc
							(start -0.1778 -0.2794)
							(mid -0.249642 -0.249642)
							(end -0.2794 -0.1778)
						)
						(arc
							(start -0.2794 0.1778)
							(mid -0.249642 0.249642)
							(end -0.1778 0.2794)
						)
						(arc
							(start 0.1778 0.2794)
							(mid 0.249642 0.249642)
							(end 0.2794 0.1778)
						)
						(arc
							(start 0.2794 -0.1778)
							(mid 0.249642 -0.249642)
							(end 0.1778 -0.2794)
						)
					)
					(width 0)
					(fill yes)
				)
			)
		)
		(pad "2" smd custom
			(at 0 0.4445 90)
			(size 0.1397 0.1397)
			(layers "F.Cu" "F.Mask" "F.Paste")
			(net "SAS2X28_A_HDD7_FLT")
			(options
				(clearance outline)
				(anchor circle)
			)
			(primitives
				(gr_poly
					(pts
						(arc
							(start -0.1778 -0.2794)
							(mid -0.249642 -0.249642)
							(end -0.2794 -0.1778)
						)
						(arc
							(start -0.2794 0.1778)
							(mid -0.249642 0.249642)
							(end -0.1778 0.2794)
						)
						(arc
							(start 0.1778 0.2794)
							(mid 0.249642 0.249642)
							(end 0.2794 0.1778)
						)
						(arc
							(start 0.2794 -0.1778)
							(mid 0.249642 -0.249642)
							(end 0.1778 -0.2794)
						)
					)
					(width 0)
					(fill yes)
				)
			)
		)
	)
)
